# T6G (Grand Teton) — schematic netlist excerpt (pin names and nets, part order shuffled) for the footprints in the layout excerpt that follows; sources: Cadence DE-HDL packaged netlist, KiCad conversion of 04192023_DAF0TMB3IC0_F0TG_MB_C_brd_V02_OCP.brd

J120  PICOPROBE_BXA  DELTA-L 4.0 EMPTY  pkg TRIANG_LAUNCH_3PXB  page 229
  \1_p\  = DELTA_L_85_10INCH_IN5_DN
  \2_n\  = DELTA_L_85_10INCH_IN5_DP
  \3_g\  = DELTA_L_GND_1

(kicad_pcb
	(version 20260206)
	(generator "pcbnew")
	(generator_version "10.0")
	(general
		(thickness 1.6)
		(legacy_teardrops no)
	)
	(paper "A4")
	(title_block
		(title "04192023_DAF0TMB3IC0_F0TG_MB_C_brd_V02_OCP.brd")
		(comment 1 "Grand Teton / footprints 6488-6488 of 8354")
	)
	(layers
		(0 "F.Cu" signal "TOP")
		(4 "In1.Cu" signal "GND")
		(6 "In2.Cu" signal "IN1")
		(8 "In3.Cu" signal "GND1")
		(10 "In4.Cu" signal "IN2")
		(12 "In5.Cu" signal "GND2")
		(14 "In6.Cu" signal "IN3")
		(16 "In7.Cu" signal "GND3")
		(18 "In8.Cu" signal "VCC")
		(20 "In9.Cu" signal "VCC1")
		(22 "In10.Cu" signal "GND4")
		(24 "In11.Cu" signal "IN4")
		(26 "In12.Cu" signal "GND5")
		(28 "In13.Cu" signal "IN5")
		(30 "In14.Cu" signal "GND6")
		(32 "In15.Cu" signal "IN6")
		(34 "In16.Cu" signal "GND7")
		(2 "B.Cu" signal "BOTTOM")
		(9 "F.Adhes" user "F.Adhesive")
		(11 "B.Adhes" user "B.Adhesive")
		(13 "F.Paste" user "Package Geometry/Pastemask Top")
		(15 "B.Paste" user "Package Geometry/Pastemask Bottom")
		(5 "F.SilkS" user "Ref Des/Silkscreen Top")
		(7 "B.SilkS" user "Ref Des/Silkscreen Bottom")
		(1 "F.Mask" user "Board Geometry/Soldermask Top")
		(3 "B.Mask" user "Board Geometry/Soldermask Bottom")
		(17 "Dwgs.User" user "User.Drawings")
		(19 "Cmts.User" user "User.Comments")
		(21 "Eco1.User" user "User.Eco1")
		(23 "Eco2.User" user "User.Eco2")
		(25 "Edge.Cuts" user "Board Geometry/Outline")
		(27 "Margin" user)
		(31 "F.CrtYd" user "Package Geometry/Place Bound Top")
		(29 "B.CrtYd" user "Package Geometry/Place Bound Bottom")
		(35 "F.Fab" user "Ref Des/Assembly Top")
		(33 "B.Fab" user "Ref Des/Assembly Bottom")
	)
	(footprint ""
		(layer "B.Cu")
		(at 185.862722 3.523234)
		(property "Reference" "J120"
			(at 4.65455 1.527302 270)
			(unlocked yes)
			(layer "B.SilkS")
			(effects
				(font
					(size 0.7874 0.5842)
					(thickness 0.1524)
				)
				(justify left mirror)
			)
		)
		(property "Value" ""
			(at 0 0 0)
			(layer "B.Fab")
			(effects
				(font
					(size 1.27 1.27)
				)
				(justify mirror)
			)
		)
		(duplicate_pad_numbers_are_jumpers no)
		(fp_line
			(start -1.2192 -2.06756)
			(end -1.2192 2.06756)
			(stroke
				(width 0.1524)
				(type default)
			)
			(layer "B.SilkS")
		)
		(fp_line
			(start -1.2192 2.06756)
			(end 1.2192 2.06756)
			(stroke
				(width 0.1524)
				(type default)
			)
			(layer "B.SilkS")
		)
		(fp_line
			(start 1.2192 -2.06756)
			(end -1.2192 -2.06756)
			(stroke
				(width 0.1524)
				(type default)
			)
			(layer "B.SilkS")
		)
		(fp_line
			(start 1.2192 2.06756)
			(end 1.2192 -2.06756)
			(stroke
				(width 0.1524)
				(type default)
			)
			(layer "B.SilkS")
		)
		(pad "" np_thru_hole circle
			(at -3.4671 -1.27 270)
			(size 1.0414 1.0414)
			(drill 1.0414)
			(layers "*.Cu" "*.Mask")
			(clearance 0.381)
			(thermal_gap 0.381)
		)
		(pad "" np_thru_hole circle
			(at -3.4671 1.27 270)
			(size 1.0414 1.0414)
			(drill 1.0414)
			(layers "*.Cu" "*.Mask")
			(clearance 0.381)
			(thermal_gap 0.381)
		)
		(pad "" np_thru_hole circle
			(at 2.8829 -1.27 270)
			(size 1.0414 1.0414)
			(drill 1.0414)
			(layers "*.Cu" "*.Mask")
			(clearance 0.381)
			(thermal_gap 0.381)
		)
		(pad "" np_thru_hole circle
			(at 2.8829 1.27 270)
			(size 1.0414 1.0414)
			(drill 1.0414)
			(layers "*.Cu" "*.Mask")
			(clearance 0.381)
			(thermal_gap 0.381)
		)
		(pad "1" smd rect
			(at -0.8255 -0.249936 270)
			(size 0.3048 0.508)
			(layers "B.Cu" "B.Mask" "B.Paste")
			(net "DELTA_L_85_10INCH_IN5_DN")
		)
		(pad "2" smd rect
			(at -0.8255 0.249936 270)
			(size 0.3048 0.508)
			(layers "B.Cu" "B.Mask" "B.Paste")
			(net "DELTA_L_85_10INCH_IN5_DP")
		)
		(pad "3" smd circle
			(at 0 0 180)
			(size 0 0)
			(layers "B.Cu" "B.Mask" "B.Paste")
			(net "DELTA_L_GND_1")
		)
		(zone
			(layers "F.Cu" "B.Cu" "In1.Cu" "In2.Cu" "In3.Cu" "In4.Cu" "In5.Cu" "In6.Cu"
				"In7.Cu" "In8.Cu" "In9.Cu" "In10.Cu" "In11.Cu" "In12.Cu" "In13.Cu" "In14.Cu"
				"In15.Cu" "In16.Cu"
			)
			(hatch none 0.5)
			(connect_pads
				(clearance 0)
			)
			(min_thickness 0.25)
			(keepout
				(tracks not_allowed)
				(vias allowed)
				(pads allowed)
				(copperpour not_allowed)
				(footprints allowed)
			)
			(placement
				(enabled no)
				(sheetname "")
			)
			(fill
				(thermal_gap 0.5)
				(thermal_bridge_width 0.5)
				(island_removal_mode 0)
			)
			(polygon
				(pts
					(arc
						(start 183.322722 2.253234)
						(mid 181.468522 2.253234)
						(end 183.322722 2.253234)
					)
				)
			)
		)
		(zone
			(layers "F.Cu" "B.Cu" "In1.Cu" "In2.Cu" "In3.Cu" "In4.Cu" "In5.Cu" "In6.Cu"
				"In7.Cu" "In8.Cu" "In9.Cu" "In10.Cu" "In11.Cu" "In12.Cu" "In13.Cu" "In14.Cu"
				"In15.Cu" "In16.Cu"
			)
			(hatch none 0.5)
			(connect_pads
				(clearance 0)
			)
			(min_thickness 0.25)
			(keepout
				(tracks not_allowed)
				(vias allowed)
				(pads allowed)
				(copperpour not_allowed)
				(footprints allowed)
			)
			(placement
				(enabled no)
				(sheetname "")
			)
			(fill
				(thermal_gap 0.5)
				(thermal_bridge_width 0.5)
				(island_removal_mode 0)
			)
			(polygon
				(pts
					(arc
						(start 183.322722 4.793234)
						(mid 181.468522 4.793234)
						(end 183.322722 4.793234)
					)
				)
			)
		)
		(zone
			(layers "F.Cu" "B.Cu" "In1.Cu" "In2.Cu" "In3.Cu" "In4.Cu" "In5.Cu" "In6.Cu"
				"In7.Cu" "In8.Cu" "In9.Cu" "In10.Cu" "In11.Cu" "In12.Cu" "In13.Cu" "In14.Cu"
				"In15.Cu" "In16.Cu"
			)
			(hatch none 0.5)
			(connect_pads
				(clearance 0)
			)
			(min_thickness 0.25)
			(keepout
				(tracks not_allowed)
				(vias allowed)
				(pads allowed)
				(copperpour not_allowed)
				(footprints allowed)
			)
			(placement
				(enabled no)
				(sheetname "")
			)
			(fill
				(thermal_gap 0.5)
				(thermal_bridge_width 0.5)
				(island_removal_mode 0)
			)
			(polygon
				(pts
					(arc
						(start 189.672722 2.253234)
						(mid 187.818522 2.253234)
						(end 189.672722 2.253234)
					)
				)
			)
		)
		(zone
			(layers "F.Cu" "B.Cu" "In1.Cu" "In2.Cu" "In3.Cu" "In4.Cu" "In5.Cu" "In6.Cu"
				"In7.Cu" "In8.Cu" "In9.Cu" "In10.Cu" "In11.Cu" "In12.Cu" "In13.Cu" "In14.Cu"
				"In15.Cu" "In16.Cu"
			)
			(hatch none 0.5)
			(connect_pads
				(clearance 0)
			)
			(min_thickness 0.25)
			(keepout
				(tracks not_allowed)
				(vias allowed)
				(pads allowed)
				(copperpour not_allowed)
				(footprints allowed)
			)
			(placement
				(enabled no)
				(sheetname "")
			)
			(fill
				(thermal_gap 0.5)
				(thermal_bridge_width 0.5)
				(island_removal_mode 0)
			)
			(polygon
				(pts
					(arc
						(start 189.672722 4.793234)
						(mid 187.818522 4.793234)
						(end 189.672722 4.793234)
					)
				)
			)
		)
		(zone
			(layer "B.Cu")
			(hatch none 0.5)
			(connect_pads
				(clearance 0)
			)
			(min_thickness 0.25)
			(keepout
				(tracks not_allowed)
				(vias allowed)
				(pads allowed)
				(copperpour not_allowed)
				(footprints allowed)
			)
			(placement
				(enabled no)
				(sheetname "")
			)
			(fill
				(thermal_gap 0.5)
				(thermal_bridge_width 0.5)
				(island_removal_mode 0)
			)
			(polygon
				(pts
					(xy 184.745122 2.974594) (xy 184.745122 3.070098) (xy 185.342022 3.070098) (xy 185.342022 3.476498)
					(xy 184.745122 3.476498) (xy 184.745122 3.56997) (xy 185.342022 3.56997) (xy 185.342022 3.97637)
					(xy 184.745122 3.97637) (xy 184.745122 4.071874) (xy 185.443622 4.071874) (xy 185.443622 2.974594)
				)
			)
		)
	)
)
